# T6G (Grand Teton) — schematic netlist excerpt (pin names and nets, part order shuffled) for the footprints in the layout excerpt that follows; sources: Cadence DE-HDL packaged netlist, KiCad conversion of 04192023_DAF0TMB3IC0_F0TG_MB_C_brd_V02_OCP.brd

C7034  Q_CAP  47UF 4V 20% X6S  pkg C0805  page 279 : A = P0V9_CPU0_RT_2D ; B = GND

PR2532  Q_SP_RES4P  0.0003 1% CHIP  pkg R2725_4P  page 266
  \1a\  = P12V_PSU
  \1b\  = P12V_HSC_SENSE2_R2_P
  \2a\  = P12V_MAIN_R
  \2b\  = P12V_HSC_SENSE2_R2_N

R4092  Q_RES  1K 1% CHIP  pkg 0402LF  page 237 : A = P3V3_AUX ; B = OCP_V3_2_P3V3_ADC_ALERT_R

(kicad_pcb
	(version 20260206)
	(generator "pcbnew")
	(generator_version "10.0")
	(general
		(thickness 1.6)
		(legacy_teardrops no)
	)
	(paper "A4")
	(title_block
		(title "04192023_DAF0TMB3IC0_F0TG_MB_C_brd_V02_OCP.brd")
		(comment 1 "Grand Teton / footprints 3060-3062 of 8354")
	)
	(layers
		(0 "F.Cu" signal "TOP")
		(4 "In1.Cu" signal "GND")
		(6 "In2.Cu" signal "IN1")
		(8 "In3.Cu" signal "GND1")
		(10 "In4.Cu" signal "IN2")
		(12 "In5.Cu" signal "GND2")
		(14 "In6.Cu" signal "IN3")
		(16 "In7.Cu" signal "GND3")
		(18 "In8.Cu" signal "VCC")
		(20 "In9.Cu" signal "VCC1")
		(22 "In10.Cu" signal "GND4")
		(24 "In11.Cu" signal "IN4")
		(26 "In12.Cu" signal "GND5")
		(28 "In13.Cu" signal "IN5")
		(30 "In14.Cu" signal "GND6")
		(32 "In15.Cu" signal "IN6")
		(34 "In16.Cu" signal "GND7")
		(2 "B.Cu" signal "BOTTOM")
		(9 "F.Adhes" user "F.Adhesive")
		(11 "B.Adhes" user "B.Adhesive")
		(13 "F.Paste" user "Package Geometry/Pastemask Top")
		(15 "B.Paste" user "Package Geometry/Pastemask Bottom")
		(5 "F.SilkS" user "Ref Des/Silkscreen Top")
		(7 "B.SilkS" user "Ref Des/Silkscreen Bottom")
		(1 "F.Mask" user "Board Geometry/Soldermask Top")
		(3 "B.Mask" user "Board Geometry/Soldermask Bottom")
		(17 "Dwgs.User" user "User.Drawings")
		(19 "Cmts.User" user "User.Comments")
		(21 "Eco1.User" user "User.Eco1")
		(23 "Eco2.User" user "User.Eco2")
		(25 "Edge.Cuts" user "Board Geometry/Outline")
		(27 "Margin" user)
		(31 "F.CrtYd" user "Package Geometry/Place Bound Top")
		(29 "B.CrtYd" user "Package Geometry/Place Bound Bottom")
		(35 "F.Fab" user "Ref Des/Assembly Top")
		(33 "B.Fab" user "Ref Des/Assembly Bottom")
	)
	(footprint ""
		(layer "F.Cu")
		(at 268.197584 -393.91336 -90)
		(property "Reference" "PR2532"
			(at -4.57454 2.978404 90)
			(unlocked yes)
			(layer "F.SilkS")
			(effects
				(font
					(size 0.7874 0.5842)
					(thickness 0.1524)
				)
				(justify left)
			)
		)
		(property "Value" ""
			(at 0 0 270)
			(layer "F.Fab")
			(effects
				(font
					(size 1.27 1.27)
				)
			)
		)
		(duplicate_pad_numbers_are_jumpers no)
		(fp_line
			(start -3.9878 3.5814)
			(end -3.9878 -3.5814)
			(stroke
				(width 0.1524)
				(type default)
			)
			(layer "F.SilkS")
		)
		(fp_line
			(start 3.9878 3.5814)
			(end -3.9878 3.5814)
			(stroke
				(width 0.1524)
				(type default)
			)
			(layer "F.SilkS")
		)
		(fp_line
			(start -3.9878 -3.5814)
			(end 3.9878 -3.5814)
			(stroke
				(width 0.1524)
				(type default)
			)
			(layer "F.SilkS")
		)
		(fp_line
			(start 3.9878 -3.5814)
			(end 3.9878 3.5814)
			(stroke
				(width 0.1524)
				(type default)
			)
			(layer "F.SilkS")
		)
		(fp_line
			(start -3.5306 3.353054)
			(end -3.5306 -3.353054)
			(stroke
				(width 0.1)
				(type default)
			)
			(layer "F.Fab")
		)
		(fp_line
			(start 3.5306 3.353054)
			(end -3.5306 3.353054)
			(stroke
				(width 0.1)
				(type default)
			)
			(layer "F.Fab")
		)
		(fp_line
			(start -3.5306 -3.353054)
			(end 3.5306 -3.353054)
			(stroke
				(width 0.1)
				(type default)
			)
			(layer "F.Fab")
		)
		(fp_line
			(start 3.5306 -3.353054)
			(end 3.5306 3.353054)
			(stroke
				(width 0.1)
				(type default)
			)
			(layer "F.Fab")
		)
		(pad "1A" smd rect
			(at -2.249932 0 90)
			(size 3.2004 6.858)
			(layers "F.Cu" "F.Mask" "F.Paste")
			(net "P12V_PSU")
		)
		(pad "1B" smd rect
			(at -0.776732 0 270)
			(size 0.254 0.508)
			(layers "F.Cu" "F.Mask" "F.Paste")
			(net "P12V_HSC_SENSE2_R2_P")
		)
		(pad "2A" smd rect
			(at 2.249932 0 90)
			(size 3.2004 6.858)
			(layers "F.Cu" "F.Mask" "F.Paste")
			(net "P12V_MAIN_R")
		)
		(pad "2B" smd rect
			(at 0.776732 0 270)
			(size 0.254 0.508)
			(layers "F.Cu" "F.Mask" "F.Paste")
			(net "P12V_HSC_SENSE2_R2_N")
		)
	)
	(footprint ""
		(layer "F.Cu")
		(at 308.002432 -410.406596 90)
		(property "Reference" "C7034"
			(at 0 0 90)
			(layer "F.SilkS")
			(hide yes)
			(effects
				(font
					(size 1.27 1.27)
				)
			)
		)
		(property "Value" ""
			(at 0 0 90)
			(layer "F.Fab")
			(effects
				(font
					(size 1.27 1.27)
				)
			)
		)
		(duplicate_pad_numbers_are_jumpers no)
		(fp_line
			(start 1.524 -0.762)
			(end 1.524 0.762)
			(stroke
				(width 0.1524)
				(type default)
			)
			(layer "F.SilkS")
		)
		(fp_line
			(start -1.524 -0.762)
			(end 1.524 -0.762)
			(stroke
				(width 0.1524)
				(type default)
			)
			(layer "F.SilkS")
		)
		(fp_line
			(start 1.524 0.762)
			(end -1.524 0.762)
			(stroke
				(width 0.1524)
				(type default)
			)
			(layer "F.SilkS")
		)
		(fp_line
			(start -1.524 0.762)
			(end -1.524 -0.762)
			(stroke
				(width 0.1524)
				(type default)
			)
			(layer "F.SilkS")
		)
		(fp_line
			(start 1.1049 -0.724916)
			(end -1.1049 -0.724916)
			(stroke
				(width 0.1)
				(type default)
			)
			(layer "F.Fab")
		)
		(fp_line
			(start -1.1049 -0.724916)
			(end -1.1049 0.724916)
			(stroke
				(width 0.1)
				(type default)
			)
			(layer "F.Fab")
		)
		(fp_line
			(start 1.1049 0.724916)
			(end 1.1049 -0.724916)
			(stroke
				(width 0.1)
				(type default)
			)
			(layer "F.Fab")
		)
		(fp_line
			(start -1.1049 0.724916)
			(end 1.1049 0.724916)
			(stroke
				(width 0.1)
				(type default)
			)
			(layer "F.Fab")
		)
		(pad "1" smd rect
			(at -0.889 0 270)
			(size 1.016 1.27)
			(layers "F.Cu" "F.Mask" "F.Paste")
			(net "P0V9_CPU0_RT_2D")
		)
		(pad "2" smd rect
			(at 0.889 0 270)
			(size 1.016 1.27)
			(layers "F.Cu" "F.Mask" "F.Paste")
			(net "GND")
		)
	)
	(footprint ""
		(layer "F.Cu")
		(at 68.2117 -36.294568)
		(property "Reference" "R4092"
			(at 0 0 0)
			(layer "F.SilkS")
			(hide yes)
			(effects
				(font
					(size 1.27 1.27)
				)
			)
		)
		(property "Value" ""
			(at 0 0 0)
			(layer "F.Fab")
			(effects
				(font
					(size 1.27 1.27)
				)
			)
		)
		(duplicate_pad_numbers_are_jumpers no)
		(fp_line
			(start -0.7874 -0.4064)
			(end 0.7874 -0.4064)
			(stroke
				(width 0.1524)
				(type default)
			)
			(layer "F.SilkS")
		)
		(fp_line
			(start -0.7874 0.4064)
			(end -0.7874 -0.4064)
			(stroke
				(width 0.1524)
				(type default)
			)
			(layer "F.SilkS")
		)
		(fp_line
			(start 0.7874 -0.4064)
			(end 0.7874 0.4064)
			(stroke
				(width 0.1524)
				(type default)
			)
			(layer "F.SilkS")
		)
		(fp_line
			(start 0.7874 0.4064)
			(end -0.7874 0.4064)
			(stroke
				(width 0.1524)
				(type default)
			)
			(layer "F.SilkS")
		)
		(fp_line
			(start -0.67945 -0.305054)
			(end -0.12065 -0.305054)
			(stroke
				(width 0.1)
				(type default)
			)
			(layer "F.Fab")
		)
		(fp_line
			(start -0.67945 0.3048)
			(end -0.67945 -0.305054)
			(stroke
				(width 0.1)
				(type default)
			)
			(layer "F.Fab")
		)
		(fp_line
			(start -0.12065 -0.305054)
			(end -0.12065 -0.2794)
			(stroke
				(width 0.1)
				(type default)
			)
			(layer "F.Fab")
		)
		(fp_line
			(start -0.12065 -0.2794)
			(end 0.12065 -0.2794)
			(stroke
				(width 0.1)
				(type default)
			)
			(layer "F.Fab")
		)
		(fp_line
			(start -0.12065 0.2794)
			(end -0.12065 0.3048)
			(stroke
				(width 0.1)
				(type default)
			)
			(layer "F.Fab")
		)
		(fp_line
			(start -0.12065 0.3048)
			(end -0.67945 0.3048)
			(stroke
				(width 0.1)
				(type default)
			)
			(layer "F.Fab")
		)
		(fp_line
			(start 0.120396 0.2794)
			(end -0.12065 0.2794)
			(stroke
				(width 0.1)
				(type default)
			)
			(layer "F.Fab")
		)
		(fp_line
			(start 0.120396 0.3048)
			(end 0.120396 0.2794)
			(stroke
				(width 0.1)
				(type default)
			)
			(layer "F.Fab")
		)
		(fp_line
			(start 0.12065 -0.3048)
			(end 0.67945 -0.3048)
			(stroke
				(width 0.1)
				(type default)
			)
			(layer "F.Fab")
		)
		(fp_line
			(start 0.12065 -0.2794)
			(end 0.12065 -0.3048)
			(stroke
				(width 0.1)
				(type default)
			)
			(layer "F.Fab")
		)
		(fp_line
			(start 0.67945 -0.3048)
			(end 0.67945 0.3048)
			(stroke
				(width 0.1)
				(type default)
			)
			(layer "F.Fab")
		)
		(fp_line
			(start 0.67945 0.3048)
			(end 0.120396 0.3048)
			(stroke
				(width 0.1)
				(type default)
			)
			(layer "F.Fab")
		)
		(pad "1" smd circle
			(at -0.40005 0)
			(size 0 0)
			(layers "F.Cu" "F.Mask" "F.Paste")
			(net "P3V3_AUX")
		)
		(pad "2" smd circle
			(at 0.40005 0)
			(size 0 0)
			(layers "F.Cu" "F.Mask" "F.Paste")
			(net "OCP_V3_2_P3V3_ADC_ALERT_R")
		)
	)
)
